FILE_TYPE = CONNECTIVITY;
{Allegro Design Entry HDL 17.4-2019 S026 (4007227) 1/17/2022}
"PAGE_NUMBER" = 71;
0"NC";
1"PVDDCR_SOC_P1\g";
2"GND\g";
3"PVDDCR_SOC_P1\g";
4"GND\g";
5"PVDD11_S3_P1\g";
6"GND\g";
7"PVDD11_S3_P1\g";
8"GND\g";
9"PVDDCR_SOC_P1\g";
10"GND\g";
11"PVDD18_S5_P1\g";
12"GND\g";
13"GND\g";
14"PVDDIO_P1\g";
%"Q_CAP"
"1","(-8500,825)","0","pure_quanta","I1";
;
LOCATION"C2262"
$SEC"1"
CDS_SEC"1"
MATERIAL"X6S"
TOLERANCE"20%"
VALUE"22UF"
VOLTAGE"4V"
PACK_TYPE"C0402"
CDS_LIB"pure_quanta"
PART_NUMBER"CH622KMEB02";
"B"
$PN"2"8;
"A"
$PN"1"7;
%"UNIVERSAL_POWER"
"1","(-8525,5175)","0","pure_quanta_power","I10";
;
HDL_POWER"PVDDCR_SOC_P1"
CDS_LIB"pure_quanta_power";
"A"1;
%"Q_CAP"
"1","(-8050,825)","0","pure_quanta","I11";
;
LOCATION"C2267"
$SEC"1"
CDS_SEC"1"
MATERIAL"X6S"
TOLERANCE"20%"
VALUE"22UF"
VOLTAGE"4V"
PACK_TYPE"C0402"
CDS_LIB"pure_quanta"
PART_NUMBER"CH622KMEB02";
"B"
$PN"2"8;
"A"
$PN"1"7;
%"Q_CAP"
"1","(-7600,825)","0","pure_quanta","I12";
;
LOCATION"C3902"
$SEC"1"
CDS_SEC"1"
MATERIAL"X6S"
TOLERANCE"20%"
VALUE"22UF"
VOLTAGE"4V"
PACK_TYPE"C0402"
CDS_LIB"pure_quanta"
PART_NUMBER"CH622KMEB02";
"B"
$PN"2"8;
"A"
$PN"1"7;
%"Q_CAP"
"1","(-8050,1575)","0","pure_quanta","I13";
;
LOCATION"C2266"
$SEC"1"
CDS_SEC"1"
MATERIAL"X6S"
TOLERANCE"20%"
VALUE"22UF"
VOLTAGE"4V"
PACK_TYPE"C0402"
CDS_LIB"pure_quanta"
PART_NUMBER"CH622KMEB02";
"B"
$PN"2"6;
"A"
$PN"1"5;
%"Q_CAP"
"1","(-7600,1575)","0","pure_quanta","I14";
;
LOCATION"C2271"
$SEC"1"
CDS_SEC"1"
MATERIAL"X6S"
TOLERANCE"20%"
VALUE"22UF"
VOLTAGE"4V"
PACK_TYPE"C0402"
CDS_LIB"pure_quanta"
PART_NUMBER"CH622KMEB02";
"B"
$PN"2"6;
"A"
$PN"1"5;
%"Q_CAP"
"1","(-7150,825)","0","pure_quanta","I15";
;
LOCATION"C3903"
$SEC"1"
CDS_SEC"1"
MATERIAL"X6S"
TOLERANCE"20%"
VALUE"22UF"
VOLTAGE"4V"
PACK_TYPE"C0402"
CDS_LIB"pure_quanta"
PART_NUMBER"CH622KMEB02";
"B"
$PN"2"8;
"A"
$PN"1"7;
%"Q_CAP"
"1","(-6700,825)","0","pure_quanta","I16";
;
LOCATION"C3904"
$SEC"1"
CDS_SEC"1"
MATERIAL"X6S"
TOLERANCE"20%"
VALUE"22UF"
VOLTAGE"4V"
PACK_TYPE"C0402"
CDS_LIB"pure_quanta"
PART_NUMBER"CH622KMEB02";
"B"
$PN"2"8;
"A"
$PN"1"7;
%"UNIVERSAL_GND"
"1","(-6250,450)","0","pure_quanta_power","I17";
;
CDS_LIB"pure_quanta_power"
HDL_POWER"GND";
"A"8;
%"Q_CAP"
"1","(-6250,825)","0","pure_quanta","I18";
;
LOCATION"C3905"
$SEC"1"
CDS_SEC"1"
MATERIAL"X6S"
TOLERANCE"20%"
VALUE"22UF"
VOLTAGE"4V"
PACK_TYPE"C0402"
CDS_LIB"pure_quanta"
PART_NUMBER"CH622KMEB02";
"B"
$PN"2"8;
"A"
$PN"1"7;
%"Q_CAP"
"1","(-7150,1575)","0","pure_quanta","I19";
;
LOCATION"C2275"
$SEC"1"
CDS_SEC"1"
MATERIAL"X6S"
TOLERANCE"20%"
VALUE"22UF"
VOLTAGE"4V"
PACK_TYPE"C0402"
CDS_LIB"pure_quanta"
PART_NUMBER"CH622KMEB02";
"B"
$PN"2"6;
"A"
$PN"1"5;
%"UNIVERSAL_POWER"
"1","(-8500,1100)","0","pure_quanta_power","I2";
;
HDL_POWER"PVDD11_S3_P1"
CDS_LIB"pure_quanta_power";
"A"7;
%"Q_CAP"
"1","(-6700,1575)","0","pure_quanta","I20";
;
LOCATION"C2279"
$SEC"1"
CDS_SEC"1"
MATERIAL"X6S"
TOLERANCE"20%"
VALUE"22UF"
VOLTAGE"4V"
PACK_TYPE"C0402"
CDS_LIB"pure_quanta"
PART_NUMBER"CH622KMEB02";
"B"
$PN"2"6;
"A"
$PN"1"5;
%"Q_CAP"
"1","(-6250,1575)","0","pure_quanta","I21";
;
LOCATION"C2282"
$SEC"1"
CDS_SEC"1"
MATERIAL"X6S"
TOLERANCE"20%"
VALUE"22UF"
VOLTAGE"4V"
PACK_TYPE"C0402"
CDS_LIB"pure_quanta"
PART_NUMBER"CH622KMEB02";
"B"
$PN"2"6;
"A"
$PN"1"5;
%"UNIVERSAL_GND"
"1","(-8075,3025)","0","pure_quanta_power","I22";
;
CDS_LIB"pure_quanta_power"
HDL_POWER"GND";
"A"10;
%"Q_CAP"
"1","(-8075,3375)","0","pure_quanta","I23";
;
LOCATION"C3901"
$SEC"1"
CDS_SEC"1"
MATERIAL"X6S"
TOLERANCE"20%"
VALUE"22UF"
VOLTAGE"4V"
PACK_TYPE"C0402"
CDS_LIB"pure_quanta"
PART_NUMBER"CH622KMEB02";
"B"
$PN"2"10;
"A"
$PN"1"9;
%"Q_CAP"
"1","(-5800,1575)","0","pure_quanta","I24";
;
LOCATION"C2285"
$SEC"1"
CDS_SEC"1"
MATERIAL"X6S"
TOLERANCE"20%"
VALUE"22UF"
VOLTAGE"4V"
PACK_TYPE"C0402"
CDS_LIB"pure_quanta"
PART_NUMBER"CH622KMEB02";
"B"
$PN"2"6;
"A"
$PN"1"5;
%"Q_CAP"
"1","(-5350,1575)","0","pure_quanta","I25";
;
LOCATION"C2287"
$SEC"1"
CDS_SEC"1"
MATERIAL"X6S"
TOLERANCE"20%"
VALUE"22UF"
VOLTAGE"4V"
PACK_TYPE"C0402"
CDS_LIB"pure_quanta"
PART_NUMBER"CH622KMEB02";
"B"
$PN"2"6;
"A"
$PN"1"5;
%"Q_CAP"
"1","(-4900,1575)","0","pure_quanta","I26";
;
LOCATION"C2289"
$SEC"1"
CDS_SEC"1"
MATERIAL"X6S"
TOLERANCE"20%"
VALUE"22UF"
VOLTAGE"4V"
PACK_TYPE"C0402"
CDS_LIB"pure_quanta"
PART_NUMBER"CH622KMEB02";
"B"
$PN"2"6;
"A"
$PN"1"5;
%"UNIVERSAL_GND"
"1","(-4500,1200)","0","pure_quanta_power","I27";
;
CDS_LIB"pure_quanta_power"
HDL_POWER"GND";
"A"6;
%"Q_CAP"
"1","(-4500,1575)","0","pure_quanta","I28";
;
LOCATION"C2291"
$SEC"1"
CDS_SEC"1"
MATERIAL"X6S"
TOLERANCE"20%"
VALUE"22UF"
VOLTAGE"4V"
PACK_TYPE"C0402"
CDS_LIB"pure_quanta"
PART_NUMBER"CH622KMEB02";
"B"
$PN"2"6;
"A"
$PN"1"5;
%"UNIVERSAL_GND"
"1","(-4525,3725)","0","pure_quanta_power","I29";
;
CDS_LIB"pure_quanta_power"
HDL_POWER"GND";
"A"4;
%"Q_CAP"
"1","(-8500,1575)","0","pure_quanta","I3";
;
LOCATION"C2261"
$SEC"1"
CDS_SEC"1"
MATERIAL"X6S"
TOLERANCE"20%"
VALUE"22UF"
VOLTAGE"4V"
PACK_TYPE"C0402"
CDS_LIB"pure_quanta"
PART_NUMBER"CH622KMEB02";
"B"
$PN"2"6;
"A"
$PN"1"5;
%"Q_CAP"
"1","(-8075,4100)","0","pure_quanta","I30";
;
LOCATION"C2264"
$SEC"1"
CDS_SEC"1"
MATERIAL"X6S"
TOLERANCE"20%"
VALUE"22UF"
VOLTAGE"4V"
PACK_TYPE"C0402"
CDS_LIB"pure_quanta"
PART_NUMBER"CH622KMEB02";
"B"
$PN"2"4;
"A"
$PN"1"3;
%"Q_CAP"
"1","(-8075,4900)","0","pure_quanta","I31";
;
LOCATION"C2263"
$SEC"1"
CDS_SEC"1"
MATERIAL"X6S"
TOLERANCE"20%"
VALUE"22UF"
VOLTAGE"4V"
PACK_TYPE"C0402"
CDS_LIB"pure_quanta"
PART_NUMBER"CH622KMEB02";
"B"
$PN"2"2;
"A"
$PN"1"1;
%"Q_CAP"
"1","(-7625,4100)","0","pure_quanta","I32";
;
LOCATION"C2269"
$SEC"1"
CDS_SEC"1"
MATERIAL"X6S"
TOLERANCE"20%"
VALUE"22UF"
VOLTAGE"4V"
PACK_TYPE"C0402"
CDS_LIB"pure_quanta"
PART_NUMBER"CH622KMEB02";
"B"
$PN"2"4;
"A"
$PN"1"3;
%"Q_CAP"
"1","(-7625,4900)","0","pure_quanta","I33";
;
LOCATION"C2268"
$SEC"1"
CDS_SEC"1"
MATERIAL"X6S"
TOLERANCE"20%"
VALUE"22UF"
VOLTAGE"4V"
PACK_TYPE"C0402"
CDS_LIB"pure_quanta"
PART_NUMBER"CH622KMEB02";
"B"
$PN"2"2;
"A"
$PN"1"1;
%"Q_CAP"
"1","(-7175,4900)","0","pure_quanta","I34";
;
LOCATION"C2272"
$SEC"1"
CDS_SEC"1"
MATERIAL"X6S"
TOLERANCE"20%"
VALUE"22UF"
VOLTAGE"4V"
PACK_TYPE"C0402"
CDS_LIB"pure_quanta"
PART_NUMBER"CH622KMEB02";
"B"
$PN"2"2;
"A"
$PN"1"1;
%"Q_CAP"
"1","(-7175,4100)","0","pure_quanta","I35";
;
LOCATION"C2273"
$SEC"1"
CDS_SEC"1"
MATERIAL"X6S"
TOLERANCE"20%"
VALUE"22UF"
VOLTAGE"4V"
PACK_TYPE"C0402"
CDS_LIB"pure_quanta"
PART_NUMBER"CH622KMEB02";
"B"
$PN"2"4;
"A"
$PN"1"3;
%"Q_CAP"
"1","(-6725,4100)","0","pure_quanta","I36";
;
LOCATION"C2277"
$SEC"1"
CDS_SEC"1"
MATERIAL"X6S"
TOLERANCE"20%"
VALUE"22UF"
VOLTAGE"4V"
PACK_TYPE"C0402"
CDS_LIB"pure_quanta"
PART_NUMBER"CH622KMEB02";
"B"
$PN"2"4;
"A"
$PN"1"3;
%"Q_CAP"
"1","(-6275,4100)","0","pure_quanta","I37";
;
LOCATION"C2281"
$SEC"1"
CDS_SEC"1"
MATERIAL"X6S"
TOLERANCE"20%"
VALUE"22UF"
VOLTAGE"4V"
PACK_TYPE"C0402"
CDS_LIB"pure_quanta"
PART_NUMBER"CH622KMEB02";
"B"
$PN"2"4;
"A"
$PN"1"3;
%"Q_CAP"
"1","(-6275,4900)","0","pure_quanta","I38";
;
LOCATION"C2280"
$SEC"1"
CDS_SEC"1"
MATERIAL"X6S"
TOLERANCE"20%"
VALUE"22UF"
VOLTAGE"4V"
PACK_TYPE"C0402"
CDS_LIB"pure_quanta"
PART_NUMBER"CH622KMEB02";
"B"
$PN"2"2;
"A"
$PN"1"1;
%"Q_CAP"
"1","(-5825,4100)","0","pure_quanta","I39";
;
LOCATION"C2284"
$SEC"1"
CDS_SEC"1"
MATERIAL"X6S"
TOLERANCE"20%"
VALUE"22UF"
VOLTAGE"4V"
PACK_TYPE"C0402"
CDS_LIB"pure_quanta"
PART_NUMBER"CH622KMEB02";
"B"
$PN"2"4;
"A"
$PN"1"3;
%"UNIVERSAL_POWER"
"1","(-8500,1850)","0","pure_quanta_power","I4";
;
HDL_POWER"PVDD11_S3_P1"
CDS_LIB"pure_quanta_power";
"A"5;
%"Q_CAP"
"1","(-5825,4900)","0","pure_quanta","I40";
;
LOCATION"C2283"
$SEC"1"
CDS_SEC"1"
MATERIAL"X6S"
TOLERANCE"20%"
VALUE"22UF"
VOLTAGE"4V"
PACK_TYPE"C0402"
CDS_LIB"pure_quanta"
PART_NUMBER"CH622KMEB02";
"B"
$PN"2"2;
"A"
$PN"1"1;
%"Q_CAP"
"1","(-5375,4100)","0","pure_quanta","I41";
;
LOCATION"C3906"
$SEC"1"
CDS_SEC"1"
MATERIAL"X6S"
TOLERANCE"20%"
VALUE"22UF"
VOLTAGE"4V"
PACK_TYPE"C0402"
CDS_LIB"pure_quanta"
PART_NUMBER"CH622KMEB02";
"B"
$PN"2"4;
"A"
$PN"1"3;
%"Q_CAP"
"1","(-5375,4900)","0","pure_quanta","I42";
;
LOCATION"C2286"
$SEC"1"
CDS_SEC"1"
MATERIAL"X6S"
TOLERANCE"20%"
VALUE"22UF"
VOLTAGE"4V"
PACK_TYPE"C0402"
CDS_LIB"pure_quanta"
PART_NUMBER"CH622KMEB02";
"B"
$PN"2"2;
"A"
$PN"1"1;
%"Q_CAP"
"1","(-4925,4100)","0","pure_quanta","I43";
;
LOCATION"C3907"
$SEC"1"
CDS_SEC"1"
MATERIAL"X6S"
TOLERANCE"20%"
VALUE"22UF"
VOLTAGE"4V"
PACK_TYPE"C0402"
CDS_LIB"pure_quanta"
PART_NUMBER"CH622KMEB02";
"B"
$PN"2"4;
"A"
$PN"1"3;
%"Q_CAP"
"1","(-4925,4900)","0","pure_quanta","I44";
;
LOCATION"C2288"
$SEC"1"
CDS_SEC"1"
MATERIAL"X6S"
TOLERANCE"20%"
VALUE"22UF"
VOLTAGE"4V"
PACK_TYPE"C0402"
CDS_LIB"pure_quanta"
PART_NUMBER"CH622KMEB02";
"B"
$PN"2"2;
"A"
$PN"1"1;
%"Q_CAP"
"1","(-4525,4100)","0","pure_quanta","I45";
;
LOCATION"C3908"
$SEC"1"
CDS_SEC"1"
MATERIAL"X6S"
TOLERANCE"20%"
VALUE"22UF"
VOLTAGE"4V"
PACK_TYPE"C0402"
CDS_LIB"pure_quanta"
PART_NUMBER"CH622KMEB02";
"B"
$PN"2"4;
"A"
$PN"1"3;
%"UNIVERSAL_GND"
"1","(-4525,4525)","0","pure_quanta_power","I46";
;
CDS_LIB"pure_quanta_power"
HDL_POWER"GND";
"A"2;
%"Q_CAP"
"1","(-4525,4900)","0","pure_quanta","I47";
;
LOCATION"C2290"
$SEC"1"
CDS_SEC"1"
MATERIAL"X6S"
TOLERANCE"20%"
VALUE"22UF"
VOLTAGE"4V"
PACK_TYPE"C0402"
CDS_LIB"pure_quanta"
PART_NUMBER"CH622KMEB02";
"B"
$PN"2"2;
"A"
$PN"1"1;
%"UNIVERSAL_POWER"
"1","(-3600,3650)","0","pure_quanta_power","I48";
;
HDL_POWER"PVDD18_S5_P1"
CDS_LIB"pure_quanta_power";
"A"11;
%"Q_CAP"
"1","(-3600,3375)","0","pure_quanta","I49";
;
LOCATION"C2292"
$SEC"1"
CDS_SEC"1"
MATERIAL"X6S"
TOLERANCE"20%"
VALUE"22UF"
VOLTAGE"4V"
PACK_TYPE"C0402"
CDS_LIB"pure_quanta"
PART_NUMBER"CH622KMEB02";
"B"
$PN"2"12;
"A"
$PN"1"11;
%"Q_CAP"
"1","(-8525,3375)","0","pure_quanta","I5";
;
LOCATION"C3900"
$SEC"1"
CDS_SEC"1"
MATERIAL"X6S"
TOLERANCE"20%"
VALUE"22UF"
VOLTAGE"4V"
PACK_TYPE"C0402"
CDS_LIB"pure_quanta"
PART_NUMBER"CH622KMEB02";
"B"
$PN"2"10;
"A"
$PN"1"9;
%"Q_CAP"
"1","(-3150,3375)","0","pure_quanta","I50";
;
LOCATION"C2293"
$SEC"1"
CDS_SEC"1"
MATERIAL"X6S"
TOLERANCE"20%"
VALUE"22UF"
VOLTAGE"4V"
PACK_TYPE"C0402"
CDS_LIB"pure_quanta"
PART_NUMBER"CH622KMEB02";
"B"
$PN"2"12;
"A"
$PN"1"11;
%"UNIVERSAL_GND"
"1","(-2700,3025)","0","pure_quanta_power","I51";
;
CDS_LIB"pure_quanta_power"
HDL_POWER"GND";
"A"12;
%"Q_CAP"
"1","(-2700,3375)","0","pure_quanta","I52";
;
LOCATION"C3909"
$SEC"1"
CDS_SEC"1"
MATERIAL"X6S"
TOLERANCE"20%"
VALUE"22UF"
VOLTAGE"4V"
PACK_TYPE"C0402"
CDS_LIB"pure_quanta"
PART_NUMBER"CH622KMEB02";
"B"
$PN"2"12;
"A"
$PN"1"11;
%"Q_CAP"
"1","(-3600,4975)","0","pure_quanta","I53";
;
LOCATION"C2260"
$SEC"1"
CDS_SEC"1"
MATERIAL"X6S"
TOLERANCE"20%"
VALUE"22UF"
VOLTAGE"4V"
PACK_TYPE"C0402"
CDS_LIB"pure_quanta"
PART_NUMBER"CH622KMEB02";
"B"
$PN"2"13;
"A"
$PN"1"14;
%"Q_CAP"
"1","(-3150,4975)","0","pure_quanta","I54";
;
LOCATION"C2265"
$SEC"1"
CDS_SEC"1"
MATERIAL"X6S"
TOLERANCE"20%"
VALUE"22UF"
VOLTAGE"4V"
PACK_TYPE"C0402"
CDS_LIB"pure_quanta"
PART_NUMBER"CH622KMEB02";
"B"
$PN"2"13;
"A"
$PN"1"14;
%"UNIVERSAL_POWER"
"1","(-3600,5250)","0","pure_quanta_power","I55";
;
HDL_POWER"PVDDIO_P1"
CDS_LIB"pure_quanta_power";
"A"14;
%"Q_CAP"
"1","(-2700,4975)","0","pure_quanta","I56";
;
LOCATION"C2270"
$SEC"1"
CDS_SEC"1"
MATERIAL"X6S"
TOLERANCE"20%"
VALUE"22UF"
VOLTAGE"4V"
PACK_TYPE"C0402"
CDS_LIB"pure_quanta"
PART_NUMBER"CH622KMEB02";
"B"
$PN"2"13;
"A"
$PN"1"14;
%"Q_CAP"
"1","(-2250,4975)","0","pure_quanta","I57";
;
LOCATION"C2274"
$SEC"1"
CDS_SEC"1"
MATERIAL"X6S"
TOLERANCE"20%"
VALUE"22UF"
VOLTAGE"4V"
PACK_TYPE"C0402"
CDS_LIB"pure_quanta"
PART_NUMBER"CH622KMEB02";
"B"
$PN"2"13;
"A"
$PN"1"14;
%"Q_CAP"
"1","(-1800,4975)","0","pure_quanta","I58";
;
LOCATION"C2278"
$SEC"1"
CDS_SEC"1"
MATERIAL"X6S"
TOLERANCE"20%"
VALUE"22UF"
VOLTAGE"4V"
PACK_TYPE"C0402"
CDS_LIB"pure_quanta"
PART_NUMBER"CH622KMEB02";
"B"
$PN"2"13;
"A"
$PN"1"14;
%"Q_CAP"
"1","(-1350,4975)","0","pure_quanta","I59";
;
LOCATION"C3910"
$SEC"1"
CDS_SEC"1"
MATERIAL"X6S"
TOLERANCE"20%"
VALUE"22UF"
VOLTAGE"4V"
PACK_TYPE"C0402"
CDS_LIB"pure_quanta"
PART_NUMBER"CH622KMEB02";
"B"
$PN"2"13;
"A"
$PN"1"14;
%"UNIVERSAL_POWER"
"1","(-8525,3650)","0","pure_quanta_power","I6";
;
HDL_POWER"PVDDCR_SOC_P1"
CDS_LIB"pure_quanta_power";
"A"9;
%"UNIVERSAL_GND"
"1","(-900,4625)","0","pure_quanta_power","I60";
;
CDS_LIB"pure_quanta_power"
HDL_POWER"GND";
"A"13;
%"Q_CAP"
"1","(-900,4975)","0","pure_quanta","I61";
;
LOCATION"C3911"
$SEC"1"
CDS_SEC"1"
MATERIAL"X6S"
TOLERANCE"20%"
VALUE"22UF"
VOLTAGE"4V"
PACK_TYPE"C0402"
CDS_LIB"pure_quanta"
PART_NUMBER"CH622KMEB02";
"B"
$PN"2"13;
"A"
$PN"1"14;
%"Q_CAP"
"1","(-6725,4900)","0","pure_quanta","I62";
;
LOCATION"C2276"
$SEC"1"
CDS_SEC"1"
MATERIAL"X6S"
TOLERANCE"20%"
VALUE"22UF"
VOLTAGE"4V"
PACK_TYPE"C0402"
CDS_LIB"pure_quanta"
PART_NUMBER"CH622KMEB02";
"B"
$PN"2"2;
"A"
$PN"1"1;
%"Q_CAP"
"1","(-8525,4100)","0","pure_quanta","I7";
;
LOCATION"C2259"
$SEC"1"
CDS_SEC"1"
MATERIAL"X6S"
TOLERANCE"20%"
VALUE"22UF"
VOLTAGE"4V"
PACK_TYPE"C0402"
CDS_LIB"pure_quanta"
PART_NUMBER"CH622KMEB02";
"B"
$PN"2"4;
"A"
$PN"1"3;
%"UNIVERSAL_POWER"
"1","(-8525,4375)","0","pure_quanta_power","I8";
;
HDL_POWER"PVDDCR_SOC_P1"
CDS_LIB"pure_quanta_power";
"A"3;
%"Q_CAP"
"1","(-8525,4900)","0","pure_quanta","I9";
;
LOCATION"C2258"
$SEC"1"
CDS_SEC"1"
MATERIAL"X6S"
TOLERANCE"20%"
VALUE"22UF"
VOLTAGE"4V"
PACK_TYPE"C0402"
CDS_LIB"pure_quanta"
PART_NUMBER"CH622KMEB02";
"B"
$PN"2"2;
"A"
$PN"1"1;
END.
